# SCM (Grand Teton) — schematic netlist excerpt (pin names and nets, part order shuffled) for the footprints in the layout excerpt that follows; sources: Cadence DE-HDL packaged netlist, KiCad conversion of 12092022_DA0F0TMDCD0_F0T_Management_Board_D_brd_V3_OCP.brd

R149  Q_RES  10K 1% CHIP  pkg 0402LF  page 27 : A = P3V3_AUX ; B = SMB_BMC_MM12_SDA
PC270  Q_CAP  22UF 4V 20% X6S  pkg 0805  page 56 : A = P1V0_AUX ; B = GND

(kicad_pcb
	(version 20260206)
	(generator "pcbnew")
	(generator_version "10.0")
	(general
		(thickness 1.6)
		(legacy_teardrops no)
	)
	(paper "A4")
	(title_block
		(title "12092022_DA0F0TMDCD0_F0T_Management_Board_D_brd_V3_OCP.brd")
		(comment 1 "Grand Teton / footprints 853-854 of 1440")
	)
	(layers
		(0 "F.Cu" signal "TOP")
		(4 "In1.Cu" signal "GND")
		(6 "In2.Cu" signal "IN1")
		(8 "In3.Cu" signal "GND1")
		(10 "In4.Cu" signal "IN2")
		(12 "In5.Cu" signal "VCC")
		(14 "In6.Cu" signal "VCC1")
		(16 "In7.Cu" signal "IN3")
		(18 "In8.Cu" signal "GND2")
		(20 "In9.Cu" signal "IN4")
		(22 "In10.Cu" signal "GND3")
		(2 "B.Cu" signal "BOTTOM")
		(9 "F.Adhes" user "F.Adhesive")
		(11 "B.Adhes" user "B.Adhesive")
		(13 "F.Paste" user "Package Geometry/Pastemask Top")
		(15 "B.Paste" user "Package Geometry/Pastemask Bottom")
		(5 "F.SilkS" user "Ref Des/Silkscreen Top")
		(7 "B.SilkS" user "Ref Des/Silkscreen Bottom")
		(1 "F.Mask" user "Board Geometry/Soldermask Top")
		(3 "B.Mask" user "Board Geometry/Soldermask Bottom")
		(17 "Dwgs.User" user "User.Drawings")
		(19 "Cmts.User" user "User.Comments")
		(21 "Eco1.User" user "User.Eco1")
		(23 "Eco2.User" user "User.Eco2")
		(25 "Edge.Cuts" user "Board Geometry/Outline")
		(27 "Margin" user)
		(31 "F.CrtYd" user "Package Geometry/Place Bound Top")
		(29 "B.CrtYd" user "Package Geometry/Place Bound Bottom")
		(35 "F.Fab" user "Ref Des/Assembly Top")
		(33 "B.Fab" user "Ref Des/Assembly Bottom")
	)
	(footprint ""
		(layer "B.Cu")
		(at 21.971 -24.003 -90)
		(property "Reference" "PC270"
			(at 0 0 90)
			(layer "B.SilkS")
			(hide yes)
			(effects
				(font
					(size 1.27 1.27)
				)
				(justify mirror)
			)
		)
		(property "Value" ""
			(at 0 0 90)
			(layer "B.Fab")
			(effects
				(font
					(size 1.27 1.27)
				)
				(justify mirror)
			)
		)
		(duplicate_pad_numbers_are_jumpers no)
		(fp_line
			(start -1.651 0.8382)
			(end 1.651 0.8382)
			(stroke
				(width 0.1524)
				(type default)
			)
			(layer "B.SilkS")
		)
		(fp_line
			(start 0 0.8382)
			(end 0 -0.8382)
			(stroke
				(width 0.1524)
				(type default)
			)
			(layer "B.SilkS")
		)
		(fp_line
			(start 1.651 0.8382)
			(end 1.651 -0.8382)
			(stroke
				(width 0.1524)
				(type default)
			)
			(layer "B.SilkS")
		)
		(fp_line
			(start -1.651 -0.8382)
			(end -1.651 0.8382)
			(stroke
				(width 0.1524)
				(type default)
			)
			(layer "B.SilkS")
		)
		(fp_line
			(start 1.651 -0.8382)
			(end -1.651 -0.8382)
			(stroke
				(width 0.1524)
				(type default)
			)
			(layer "B.SilkS")
		)
		(fp_line
			(start -1.55956 0.7366)
			(end -1.55956 -0.7366)
			(stroke
				(width 0.1)
				(type default)
			)
			(layer "B.Fab")
		)
		(fp_line
			(start -1.524 0.7366)
			(end -1.55956 0.7366)
			(stroke
				(width 0.1)
				(type default)
			)
			(layer "B.Fab")
		)
		(fp_line
			(start 1.524 0.7366)
			(end -1.524 0.7366)
			(stroke
				(width 0.1)
				(type default)
			)
			(layer "B.Fab")
		)
		(fp_line
			(start 1.55956 0.7366)
			(end 1.524 0.7366)
			(stroke
				(width 0.1)
				(type default)
			)
			(layer "B.Fab")
		)
		(fp_line
			(start -1.55956 -0.7366)
			(end -1.524 -0.7366)
			(stroke
				(width 0.1)
				(type default)
			)
			(layer "B.Fab")
		)
		(fp_line
			(start -1.524 -0.7366)
			(end 1.524 -0.7366)
			(stroke
				(width 0.1)
				(type default)
			)
			(layer "B.Fab")
		)
		(fp_line
			(start 1.524 -0.7366)
			(end 1.55956 -0.7366)
			(stroke
				(width 0.1)
				(type default)
			)
			(layer "B.Fab")
		)
		(fp_line
			(start 1.55956 -0.7366)
			(end 1.55956 0.7366)
			(stroke
				(width 0.1)
				(type default)
			)
			(layer "B.Fab")
		)
		(pad "1" smd rect
			(at 0.94996 0 270)
			(size 1.1176 1.3716)
			(layers "B.Cu" "B.Mask" "B.Paste")
			(net "P1V0_AUX")
		)
		(pad "2" smd rect
			(at -0.94996 0 270)
			(size 1.1176 1.3716)
			(layers "B.Cu" "B.Mask" "B.Paste")
			(net "GND")
		)
	)
	(footprint ""
		(layer "B.Cu")
		(at 39.93007 -46.119542 180)
		(property "Reference" "R149"
			(at 0 0 0)
			(layer "B.SilkS")
			(hide yes)
			(effects
				(font
					(size 1.27 1.27)
				)
				(justify mirror)
			)
		)
		(property "Value" ""
			(at 0 0 0)
			(layer "B.Fab")
			(effects
				(font
					(size 1.27 1.27)
				)
				(justify mirror)
			)
		)
		(duplicate_pad_numbers_are_jumpers no)
		(fp_line
			(start 0.7874 0.4064)
			(end 0.7874 -0.4064)
			(stroke
				(width 0.1524)
				(type default)
			)
			(layer "B.SilkS")
		)
		(fp_line
			(start 0.7874 -0.4064)
			(end -0.7874 -0.4064)
			(stroke
				(width 0.1524)
				(type default)
			)
			(layer "B.SilkS")
		)
		(fp_line
			(start -0.7874 0.4064)
			(end 0.7874 0.4064)
			(stroke
				(width 0.1524)
				(type default)
			)
			(layer "B.SilkS")
		)
		(fp_line
			(start -0.7874 -0.4064)
			(end -0.7874 0.4064)
			(stroke
				(width 0.1524)
				(type default)
			)
			(layer "B.SilkS")
		)
		(fp_line
			(start 0.67945 0.3048)
			(end 0.67945 -0.305054)
			(stroke
				(width 0.1)
				(type default)
			)
			(layer "B.Fab")
		)
		(fp_line
			(start 0.67945 -0.305054)
			(end 0.12065 -0.305054)
			(stroke
				(width 0.1)
				(type default)
			)
			(layer "B.Fab")
		)
		(fp_line
			(start 0.12065 0.3048)
			(end 0.67945 0.3048)
			(stroke
				(width 0.1)
				(type default)
			)
			(layer "B.Fab")
		)
		(fp_line
			(start 0.12065 0.2794)
			(end 0.12065 0.3048)
			(stroke
				(width 0.1)
				(type default)
			)
			(layer "B.Fab")
		)
		(fp_line
			(start 0.12065 -0.2794)
			(end -0.12065 -0.2794)
			(stroke
				(width 0.1)
				(type default)
			)
			(layer "B.Fab")
		)
		(fp_line
			(start 0.12065 -0.305054)
			(end 0.12065 -0.2794)
			(stroke
				(width 0.1)
				(type default)
			)
			(layer "B.Fab")
		)
		(fp_line
			(start -0.120396 0.3048)
			(end -0.120396 0.2794)
			(stroke
				(width 0.1)
				(type default)
			)
			(layer "B.Fab")
		)
		(fp_line
			(start -0.120396 0.2794)
			(end 0.12065 0.2794)
			(stroke
				(width 0.1)
				(type default)
			)
			(layer "B.Fab")
		)
		(fp_line
			(start -0.12065 -0.2794)
			(end -0.12065 -0.3048)
			(stroke
				(width 0.1)
				(type default)
			)
			(layer "B.Fab")
		)
		(fp_line
			(start -0.12065 -0.3048)
			(end -0.67945 -0.3048)
			(stroke
				(width 0.1)
				(type default)
			)
			(layer "B.Fab")
		)
		(fp_line
			(start -0.67945 0.3048)
			(end -0.120396 0.3048)
			(stroke
				(width 0.1)
				(type default)
			)
			(layer "B.Fab")
		)
		(fp_line
			(start -0.67945 -0.3048)
			(end -0.67945 0.3048)
			(stroke
				(width 0.1)
				(type default)
			)
			(layer "B.Fab")
		)
		(pad "1" smd circle
			(at 0.40005 0)
			(size 0 0)
			(layers "B.Cu" "B.Mask" "B.Paste")
			(net "P3V3_AUX")
		)
		(pad "2" smd circle
			(at -0.40005 0)
			(size 0 0)
			(layers "B.Cu" "B.Mask" "B.Paste")
			(net "SMB_BMC_MM12_SDA")
		)
	)
)
